# T6G (Grand Teton) — schematic netlist excerpt (pin names and nets, part order shuffled) for the footprints in the layout excerpt that follows; sources: Cadence DE-HDL packaged netlist, KiCad conversion of 04192023_DAF0TMB3IC0_F0TG_MB_C_brd_V02_OCP.brd

J21  SCONN288_DDR506112002KQ  IO  pkg DDR288S_1-1VXC  page 90
  VIN_BULK0  = P12V_MEM_CPU0
  RFU0  = NC
  VIN_MGMT  = P3V3_AUX
  HSCL  = I3C_SPD_DDRE_CPU0_SCL
  HSDA  = I3C_SPD_DDRE_CPU0_SDA
  VSS0  = GND
  DQ0_A  = M_E_CPU0_SA_DQ<0>
  VSS1  = GND
  DQ1_A  = M_E_CPU0_SA_DQ<1>
  VSS2  = GND
  DQS0_A_T  = M_E_CPU0_SA_DQS_DP<0>
  DQS0_A_C  = M_E_CPU0_SA_DQS_DN<0>
  VSS3  = GND
  DQ4_A  = M_E_CPU0_SA_DQ<4>
  VSS4  = GND
  DQ5_A  = M_E_CPU0_SA_DQ<5>
  VSS5  = GND
  DQ8_A  = M_E_CPU0_SA_DQ<8>
  VSS6  = GND
  DQ9_A  = M_E_CPU0_SA_DQ<9>
  VSS7  = GND
  DQS1_A_T  = M_E_CPU0_SA_DQS_DP<1>
  DQS1_A_C  = M_E_CPU0_SA_DQS_DN<1>
  VSS8  = GND
  DQ12_A  = M_E_CPU0_SA_DQ<12>
  VSS9  = GND
  DQ13_A  = M_E_CPU0_SA_DQ<13>
  VSS10  = GND
  DQ16_A  = M_E_CPU0_SA_DQ<16>
  VSS11  = GND
  DQ17_A  = M_E_CPU0_SA_DQ<17>
  VSS12  = GND
  DQS2_A_T  = M_E_CPU0_SA_DQS_DP<2>
  DQS2_A_C  = M_E_CPU0_SA_DQS_DN<2>
  VSS13  = GND
  DQ20_A  = M_E_CPU0_SA_DQ<20>
  VSS14  = GND
  DQ21_A  = M_E_CPU0_SA_DQ<21>
  VSS15  = GND
  DQ24_A  = M_E_CPU0_SA_DQ<24>
  VSS16  = GND
  DQ25_A  = M_E_CPU0_SA_DQ<25>
  VSS17  = GND
  DQS3_A_T  = M_E_CPU0_SA_DQS_DP<3>
  DQS3_A_C  = M_E_CPU0_SA_DQS_DN<3>
  VSS18  = GND
  DQ28_A  = M_E_CPU0_SA_DQ<28>
  VSS19  = GND
  DQ29_A  = M_E_CPU0_SA_DQ<29>
  VSS20  = GND
  CB0_A  = M_E_CPU0_SA_CB<0>
  VSS21  = GND
  CB1_A  = M_E_CPU0_SA_CB<1>
  VSS22  = GND
  DQS4_A_T  = M_E_CPU0_SA_DQS_DP<4>
  DQS4_A_C  = M_E_CPU0_SA_DQS_DN<4>
  VSS23  = GND
  CB4_A  = M_E_CPU0_SA_CB<4>
  VSS24  = GND
  CB5_A  = M_E_CPU0_SA_CB<5>
  VSS25  = GND
  ALERT_N  = M_E_CPU0_ALERT_N
  VSS26  = GND
  CS0_A_N  = M_E_CPU0_SA_CS_N<0>
  VSS27  = GND
  CA0_A  = M_E_CPU0_SA_CA<0>
  VSS28  = GND
  CA2_A  = M_E_CPU0_SA_CA<2>
  VSS29  = GND
  CA4_A  = M_E_CPU0_SA_CA<4>
  VSS30  = GND
  CA6_A  = M_E_CPU0_SA_CA<6>
  VSS31  = GND
  PAR_A  = M_E_CPU0_SA_PAR
  VSS32  = GND
  CA0_B  = M_E_CPU0_SB_CA<0>
  VSS33  = GND
  CA2_B  = M_E_CPU0_SB_CA<2>
  VSS34  = GND
  CA4_B  = M_E_CPU0_SB_CA<4>
  VSS35  = GND
  CA6_B  = M_E_CPU0_SB_CA<6>
  VSS36  = GND
  CS0_B_N  = M_E_CPU0_SB_CS_N<0>
  VSS37  = GND
  \lbd||rsp_a_n\  = M_E_CPU0_SA_RSP<0>
  \lbs||rsp_b_n\  = M_E_CPU0_SB_RSP<0>
  VSS38  = GND
  CB4_B  = M_E_CPU0_SB_CB<4>
  VSS39  = GND
  CB5_B  = M_E_CPU0_SB_CB<5>
  VSS40  = GND
  \dqs9_b_t||tdqs9_b_t||dbi4_b_n\  = M_E_CPU0_SB_DQS_DP<9>
  \dqs9_b_c||tdqs9_b_c\  = M_E_CPU0_SB_DQS_DN<9>
  VSS41  = GND
  CB0_B  = M_E_CPU0_SB_CB<0>
  VSS42  = GND
  CB1_B  = M_E_CPU0_SB_CB<1>
  VSS43  = GND
  DQ0_B  = M_E_CPU0_SB_DQ<0>
  VSS44  = GND
  DQ1_B  = M_E_CPU0_SB_DQ<1>
  VSS45  = GND
  DQS0_B_T  = M_E_CPU0_SB_DQS_DP<0>
  DQS0_B_C  = M_E_CPU0_SB_DQS_DN<0>
  VSS46  = GND
  DQ4_B  = M_E_CPU0_SB_DQ<4>
  VSS47  = GND
  DQ5_B  = M_E_CPU0_SB_DQ<5>
  VSS48  = GND
  DQ8_B  = M_E_CPU0_SB_DQ<8>
  VSS49  = GND
  DQ9_B  = M_E_CPU0_SB_DQ<9>
  VSS50  = GND
  DQS1_B_T  = M_E_CPU0_SB_DQS_DP<1>
  DQS1_B_C  = M_E_CPU0_SB_DQS_DN<1>
  VSS51  = GND
  DQ12_B  = M_E_CPU0_SB_DQ<12>
  VSS52  = GND
  DQ13_B  = M_E_CPU0_SB_DQ<13>
  VSS53  = GND
  DQ16_B  = M_E_CPU0_SB_DQ<16>
  VSS54  = GND
  DQ17_B  = M_E_CPU0_SB_DQ<17>
  VSS55  = GND
  DQS2_B_T  = M_E_CPU0_SB_DQS_DP<2>
  DQS2_B_C  = M_E_CPU0_SB_DQS_DN<2>
  VSS56  = GND
  DQ20_B  = M_E_CPU0_SB_DQ<20>
  VSS57  = GND
  DQ21_B  = M_E_CPU0_SB_DQ<21>
  VSS58  = GND
  DQ24_B  = M_E_CPU0_SB_DQ<24>
  VSS59  = GND
  DQ25_B  = M_E_CPU0_SB_DQ<25>
  VSS60  = GND
  DQS3_B_T  = M_E_CPU0_SB_DQS_DP<3>
  DQS3_B_C  = M_E_CPU0_SB_DQS_DN<3>
  VSS61  = GND
  DQ28_B  = M_E_CPU0_SB_DQ<28>
  VSS62  = GND
  DQ29_B  = M_E_CPU0_SB_DQ<29>
  VSS63  = GND
  RFU1  = NC
  VIN_BULK1  = P12V_MEM_CPU0
  VIN_BULK2  = P12V_MEM_CPU0
  \pwr_good||fail_n\  = PWRGD_CHE_CPU0_DIMM
  HAS  = PD_CHE_CPU0_DIMM_SAA
  RFU2  = NC
  RFU3  = NC
  VSS64  = GND
  DQ2_A  = M_E_CPU0_SA_DQ<2>
  VSS65  = GND
  DQ3_A  = M_E_CPU0_SA_DQ<3>
  VSS66  = GND
  \dqs5_a_c||tdqs5_a_c||dqs5_a_t||tdqs5_a_t\  = M_E_CPU0_SA_DQS_DN<5>
  \dqs5_a_t||tdqs5_a_t\  = M_E_CPU0_SA_DQS_DP<5>
  VSS67  = GND
  DQ6_A  = M_E_CPU0_SA_DQ<6>
  VSS68  = GND
  DQ7_A  = M_E_CPU0_SA_DQ<7>
  VSS69  = GND
  DQ10_A  = M_E_CPU0_SA_DQ<10>
  VSS70  = GND
  DQ11_A  = M_E_CPU0_SA_DQ<11>
  VSS71  = GND
  \dqs6_a_c||tdqs6_a_c||dqs6_a_t||tdqs6_a_t\  = M_E_CPU0_SA_DQS_DN<6>
  \dqs6_a_t||tdqs6_a_t\  = M_E_CPU0_SA_DQS_DP<6>
  VSS72  = GND
  DQ14_A  = M_E_CPU0_SA_DQ<14>
  VSS73  = GND
  DQ15_A  = M_E_CPU0_SA_DQ<15>
  VSS74  = GND
  DQ18_A  = M_E_CPU0_SA_DQ<18>
  VSS75  = GND
  DQ19_A  = M_E_CPU0_SA_DQ<19>
  VSS76  = GND
  \dqs7_a_c||tdqs7_a_c\  = M_E_CPU0_SA_DQS_DN<7>
  \dqs7_a_t||tdqs7_a_t\  = M_E_CPU0_SA_DQS_DP<7>
  VSS77  = GND
  DQ22_A  = M_E_CPU0_SA_DQ<22>
  VSS78  = GND
  DQ23_A  = M_E_CPU0_SA_DQ<23>
  VSS79  = GND
  DQ26_A  = M_E_CPU0_SA_DQ<26>
  VSS80  = GND
  DQ27_A  = M_E_CPU0_SA_DQ<27>
  VSS81  = GND
  \dqs8_a_c||tdqs8_a_c\  = M_E_CPU0_SA_DQS_DN<8>
  \dqs8_a_t||tdqs8_a_t\  = M_E_CPU0_SA_DQS_DP<8>
  VSS82  = GND
  DQ30_A  = M_E_CPU0_SA_DQ<30>
  VSS83  = GND
  DQ31_A  = M_E_CPU0_SA_DQ<31>
  VSS84  = GND
  CB2_A  = M_E_CPU0_SA_CB<2>
  VSS85  = GND
  CB3_A  = M_E_CPU0_SA_CB<3>
  VSS86  = GND
  \dqs9_a_c||tdqs9_a_c\  = M_E_CPU0_SA_DQS_DN<9>
  \dqs9_a_t||tdqs9_a_t\  = M_E_CPU0_SA_DQS_DP<9>
  VSS87  = GND
  CB6_A  = M_E_CPU0_SA_CB<6>
  VSS88  = GND
  CB7_A  = M_E_CPU0_SA_CB<7>
  VSS89  = GND
  RESET_N  = M_E_CPU0_RESET_N
  VSS90  = GND
  CS1_A_N  = M_E_CPU0_SA_CS_N<1>
  VSS91  = GND
  CA1_A  = M_E_CPU0_SA_CA<1>
  VSS92  = GND
  CA3_A  = M_E_CPU0_SA_CA<3>
  VSS93  = GND
  CA5_A  = M_E_CPU0_SA_CA<5>
  VSS94  = GND
  CK_T  = M_E_CPU0_CLK_DP<0>
  CK_C  = M_E_CPU0_CLK_DN<0>
  VSS95  = GND
  RFU4  = NC
  CA1_B  = M_E_CPU0_SB_CA<1>
  VSS96  = GND
  CA3_B  = M_E_CPU0_SB_CA<3>
  VSS97  = GND
  CA5_B  = M_E_CPU0_SB_CA<5>
  VSS98  = GND
  PAR_B  = M_E_CPU0_SB_PAR
  VSS99  = GND
  CS1_B_N  = M_E_CPU0_SB_CS_N<1>
  VSS100  = GND
  RFU5  = NC
  RFU6  = NC
  VSS101  = GND
  CB6_B  = M_E_CPU0_SB_CB<6>
  VSS102  = GND
  CB7_B  = M_E_CPU0_SB_CB<7>
  VSS103  = GND
  DQS4_B_C  = M_E_CPU0_SB_DQS_DN<4>
  DQS4_B_T  = M_E_CPU0_SB_DQS_DP<4>
  VSS104  = GND
  CB2_B  = M_E_CPU0_SB_CB<2>
  VSS105  = GND
  CB3_B  = M_E_CPU0_SB_CB<3>
  VSS106  = GND
  DQ2_B  = M_E_CPU0_SB_DQ<2>
  VSS107  = GND
  DQ3_B  = M_E_CPU0_SB_DQ<3>
  VSS108  = GND
  \dqs5_b_c||tdqs5_b_c\  = M_E_CPU0_SB_DQS_DN<5>
  \dqs5_b_t||tdqs5_b_t\  = M_E_CPU0_SB_DQS_DP<5>
  VSS109  = GND
  DQ6_B  = M_E_CPU0_SB_DQ<6>
  VSS110  = GND
  DQ7_B  = M_E_CPU0_SB_DQ<7>
  VSS111  = GND
  DQ10_B  = M_E_CPU0_SB_DQ<10>
  VSS112  = GND
  DQ11_B  = M_E_CPU0_SB_DQ<11>
  VSS113  = GND
  \dqs6_b_c||tdqs6_b_c\  = M_E_CPU0_SB_DQS_DN<6>
  \dqs6_b_t||tdqs6_b_t\  = M_E_CPU0_SB_DQS_DP<6>
  VSS114  = GND
  DQ14_B  = M_E_CPU0_SB_DQ<14>
  VSS115  = GND
  DQ15_B  = M_E_CPU0_SB_DQ<15>
  VSS116  = GND
  DQ18_B  = M_E_CPU0_SB_DQ<18>
  VSS117  = GND
  DQ19_B  = M_E_CPU0_SB_DQ<19>
  VSS118  = GND
  \dqs7_b_c||tdqs7_b_c\  = M_E_CPU0_SB_DQS_DN<7>
  \dqs7_b_t||tdqs7_b_t\  = M_E_CPU0_SB_DQS_DP<7>
  VSS119  = GND
  DQ22_B  = M_E_CPU0_SB_DQ<22>
  VSS120  = GND
  DQ23_B  = M_E_CPU0_SB_DQ<23>
  VSS121  = GND
  DQ26_B  = M_E_CPU0_SB_DQ<26>
  VSS122  = GND
  DQ27_B  = M_E_CPU0_SB_DQ<27>
  VSS123  = GND
  \dqs8_b_c||tdqs8_b_c\  = M_E_CPU0_SB_DQS_DN<8>
  \dqs8_b_t||tdqs8_b_t\  = M_E_CPU0_SB_DQS_DP<8>
  VSS124  = GND
  DQ30_B  = M_E_CPU0_SB_DQ<30>
  VSS125  = GND
  DQ31_B  = M_E_CPU0_SB_DQ<31>
  VSS126  = GND
  G1  = GND
  G2  = GND
  G3  = GND

(kicad_pcb
	(version 20260206)
	(generator "pcbnew")
	(generator_version "10.0")
	(general
		(thickness 1.6)
		(legacy_teardrops no)
	)
	(paper "A4")
	(title_block
		(title "04192023_DAF0TMB3IC0_F0TG_MB_C_brd_V02_OCP.brd")
		(comment 1 "Grand Teton / footprint 3 of 8354 (J21), pads 185-230 of 291")
	)
	(layers
		(0 "F.Cu" signal "TOP")
		(4 "In1.Cu" signal "GND")
		(6 "In2.Cu" signal "IN1")
		(8 "In3.Cu" signal "GND1")
		(10 "In4.Cu" signal "IN2")
		(12 "In5.Cu" signal "GND2")
		(14 "In6.Cu" signal "IN3")
		(16 "In7.Cu" signal "GND3")
		(18 "In8.Cu" signal "VCC")
		(20 "In9.Cu" signal "VCC1")
		(22 "In10.Cu" signal "GND4")
		(24 "In11.Cu" signal "IN4")
		(26 "In12.Cu" signal "GND5")
		(28 "In13.Cu" signal "IN5")
		(30 "In14.Cu" signal "GND6")
		(32 "In15.Cu" signal "IN6")
		(34 "In16.Cu" signal "GND7")
		(2 "B.Cu" signal "BOTTOM")
		(9 "F.Adhes" user "F.Adhesive")
		(11 "B.Adhes" user "B.Adhesive")
		(13 "F.Paste" user "Package Geometry/Pastemask Top")
		(15 "B.Paste" user "Package Geometry/Pastemask Bottom")
		(5 "F.SilkS" user "Ref Des/Silkscreen Top")
		(7 "B.SilkS" user "Ref Des/Silkscreen Bottom")
		(1 "F.Mask" user "Board Geometry/Soldermask Top")
		(3 "B.Mask" user "Board Geometry/Soldermask Bottom")
		(17 "Dwgs.User" user "User.Drawings")
		(19 "Cmts.User" user "User.Comments")
		(21 "Eco1.User" user "User.Eco1")
		(23 "Eco2.User" user "User.Eco2")
		(25 "Edge.Cuts" user "Board Geometry/Outline")
		(27 "Margin" user)
		(31 "F.CrtYd" user "Package Geometry/Place Bound Top")
		(29 "B.CrtYd" user "Package Geometry/Place Bound Bottom")
		(35 "F.Fab" user "Ref Des/Assembly Top")
		(33 "B.Fab" user "Ref Des/Assembly Bottom")
	)
	(footprint ""
		(layer "F.Cu")
		(at 275.142198 -255.560068 180)
		(property "Reference" "J21"
			(at -2.2098 -81.984088 0)
			(unlocked yes)
			(layer "F.SilkS")
			(effects
				(font
					(size 0.7874 0.5842)
					(thickness 0.1524)
				)
			)
		)
		(property "Value" ""
			(at 0 0 180)
			(layer "F.Fab")
			(effects
				(font
					(size 1.27 1.27)
				)
			)
		)
		(duplicate_pad_numbers_are_jumpers no)
		(pad "185" smd rect
			(at 2.050034 -29.325062 90)
			(size 0.519938 1.4986)
			(layers "F.Cu" "F.Mask" "F.Paste")
			(net "M_E_CPU0_SA_DQ<26>")
		)
		(pad "186" smd rect
			(at 2.050034 -28.474924 90)
			(size 0.519938 1.4986)
			(layers "F.Cu" "F.Mask" "F.Paste")
			(net "GND")
		)
		(pad "187" smd rect
			(at 2.050034 -27.62504 90)
			(size 0.519938 1.4986)
			(layers "F.Cu" "F.Mask" "F.Paste")
			(net "M_E_CPU0_SA_DQ<27>")
		)
		(pad "188" smd rect
			(at 2.050034 -26.774902 90)
			(size 0.519938 1.4986)
			(layers "F.Cu" "F.Mask" "F.Paste")
			(net "GND")
		)
		(pad "189" smd rect
			(at 2.050034 -25.925018 90)
			(size 0.519938 1.4986)
			(layers "F.Cu" "F.Mask" "F.Paste")
			(net "M_E_CPU0_SA_DQS_DN<8>")
		)
		(pad "190" smd rect
			(at 2.050034 -25.07488 90)
			(size 0.519938 1.4986)
			(layers "F.Cu" "F.Mask" "F.Paste")
			(net "M_E_CPU0_SA_DQS_DP<8>")
		)
		(pad "191" smd rect
			(at 2.050034 -24.224996 90)
			(size 0.519938 1.4986)
			(layers "F.Cu" "F.Mask" "F.Paste")
			(net "GND")
		)
		(pad "192" smd rect
			(at 2.050034 -23.375112 90)
			(size 0.519938 1.4986)
			(layers "F.Cu" "F.Mask" "F.Paste")
			(net "M_E_CPU0_SA_DQ<30>")
		)
		(pad "193" smd rect
			(at 2.050034 -22.524974 90)
			(size 0.519938 1.4986)
			(layers "F.Cu" "F.Mask" "F.Paste")
			(net "GND")
		)
		(pad "194" smd rect
			(at 2.050034 -21.67509 90)
			(size 0.519938 1.4986)
			(layers "F.Cu" "F.Mask" "F.Paste")
			(net "M_E_CPU0_SA_DQ<31>")
		)
		(pad "195" smd rect
			(at 2.050034 -20.824952 90)
			(size 0.519938 1.4986)
			(layers "F.Cu" "F.Mask" "F.Paste")
			(net "GND")
		)
		(pad "196" smd rect
			(at 2.050034 -19.975068 90)
			(size 0.519938 1.4986)
			(layers "F.Cu" "F.Mask" "F.Paste")
			(net "M_E_CPU0_SA_CB<2>")
		)
		(pad "197" smd rect
			(at 2.050034 -19.12493 90)
			(size 0.519938 1.4986)
			(layers "F.Cu" "F.Mask" "F.Paste")
			(net "GND")
		)
		(pad "198" smd rect
			(at 2.050034 -18.275046 90)
			(size 0.519938 1.4986)
			(layers "F.Cu" "F.Mask" "F.Paste")
			(net "M_E_CPU0_SA_CB<3>")
		)
		(pad "199" smd rect
			(at 2.050034 -17.424908 90)
			(size 0.519938 1.4986)
			(layers "F.Cu" "F.Mask" "F.Paste")
			(net "GND")
		)
		(pad "200" smd rect
			(at 2.050034 -16.575024 90)
			(size 0.519938 1.4986)
			(layers "F.Cu" "F.Mask" "F.Paste")
			(net "M_E_CPU0_SA_DQS_DN<9>")
		)
		(pad "201" smd rect
			(at 2.050034 -15.724886 90)
			(size 0.519938 1.4986)
			(layers "F.Cu" "F.Mask" "F.Paste")
			(net "M_E_CPU0_SA_DQS_DP<9>")
		)
		(pad "202" smd rect
			(at 2.050034 -14.875002 90)
			(size 0.519938 1.4986)
			(layers "F.Cu" "F.Mask" "F.Paste")
			(net "GND")
		)
		(pad "203" smd rect
			(at 2.050034 -14.025118 90)
			(size 0.519938 1.4986)
			(layers "F.Cu" "F.Mask" "F.Paste")
			(net "M_E_CPU0_SA_CB<6>")
		)
		(pad "204" smd rect
			(at 2.050034 -13.17498 90)
			(size 0.519938 1.4986)
			(layers "F.Cu" "F.Mask" "F.Paste")
			(net "GND")
		)
		(pad "205" smd rect
			(at 2.050034 -12.325096 90)
			(size 0.519938 1.4986)
			(layers "F.Cu" "F.Mask" "F.Paste")
			(net "M_E_CPU0_SA_CB<7>")
		)
		(pad "206" smd rect
			(at 2.050034 -11.474958 90)
			(size 0.519938 1.4986)
			(layers "F.Cu" "F.Mask" "F.Paste")
			(net "GND")
		)
		(pad "207" smd rect
			(at 2.050034 -10.625074 90)
			(size 0.519938 1.4986)
			(layers "F.Cu" "F.Mask" "F.Paste")
			(net "M_E_CPU0_RESET_N")
		)
		(pad "208" smd rect
			(at 2.050034 -9.774936 90)
			(size 0.519938 1.4986)
			(layers "F.Cu" "F.Mask" "F.Paste")
			(net "GND")
		)
		(pad "209" smd rect
			(at 2.050034 -8.925052 90)
			(size 0.519938 1.4986)
			(layers "F.Cu" "F.Mask" "F.Paste")
			(net "M_E_CPU0_SA_CS_N<1>")
		)
		(pad "210" smd rect
			(at 2.050034 -8.074914 90)
			(size 0.519938 1.4986)
			(layers "F.Cu" "F.Mask" "F.Paste")
			(net "GND")
		)
		(pad "211" smd rect
			(at 2.050034 -7.22503 90)
			(size 0.519938 1.4986)
			(layers "F.Cu" "F.Mask" "F.Paste")
			(net "M_E_CPU0_SA_CA<1>")
		)
		(pad "212" smd rect
			(at 2.050034 -6.374892 90)
			(size 0.519938 1.4986)
			(layers "F.Cu" "F.Mask" "F.Paste")
			(net "GND")
		)
		(pad "213" smd rect
			(at 2.050034 -5.525008 90)
			(size 0.519938 1.4986)
			(layers "F.Cu" "F.Mask" "F.Paste")
			(net "M_E_CPU0_SA_CA<3>")
		)
		(pad "214" smd rect
			(at 2.050034 -4.675124 90)
			(size 0.519938 1.4986)
			(layers "F.Cu" "F.Mask" "F.Paste")
			(net "GND")
		)
		(pad "215" smd rect
			(at 2.050034 -3.824986 90)
			(size 0.519938 1.4986)
			(layers "F.Cu" "F.Mask" "F.Paste")
			(net "M_E_CPU0_SA_CA<5>")
		)
		(pad "216" smd rect
			(at 2.050034 -2.975102 90)
			(size 0.519938 1.4986)
			(layers "F.Cu" "F.Mask" "F.Paste")
			(net "GND")
		)
		(pad "217" smd rect
			(at 2.050034 -2.124964 90)
			(size 0.519938 1.4986)
			(layers "F.Cu" "F.Mask" "F.Paste")
			(net "M_E_CPU0_CLK_DP<0>")
		)
		(pad "218" smd rect
			(at 2.050034 -1.27508 90)
			(size 0.519938 1.4986)
			(layers "F.Cu" "F.Mask" "F.Paste")
			(net "M_E_CPU0_CLK_DN<0>")
		)
		(pad "219" smd rect
			(at 2.050034 -0.424942 90)
			(size 0.519938 1.4986)
			(layers "F.Cu" "F.Mask" "F.Paste")
			(net "GND")
		)
		(pad "220" smd rect
			(at 2.050034 5.525008 90)
			(size 0.519938 1.4986)
			(layers "F.Cu" "F.Mask" "F.Paste")
			(net "Net_2309")
		)
		(pad "221" smd rect
			(at 2.050034 6.374892 90)
			(size 0.519938 1.4986)
			(layers "F.Cu" "F.Mask" "F.Paste")
			(net "M_E_CPU0_SB_CA<1>")
		)
		(pad "222" smd rect
			(at 2.050034 7.22503 90)
			(size 0.519938 1.4986)
			(layers "F.Cu" "F.Mask" "F.Paste")
			(net "GND")
		)
		(pad "223" smd rect
			(at 2.050034 8.074914 90)
			(size 0.519938 1.4986)
			(layers "F.Cu" "F.Mask" "F.Paste")
			(net "M_E_CPU0_SB_CA<3>")
		)
		(pad "224" smd rect
			(at 2.050034 8.925052 90)
			(size 0.519938 1.4986)
			(layers "F.Cu" "F.Mask" "F.Paste")
			(net "GND")
		)
		(pad "225" smd rect
			(at 2.050034 9.774936 90)
			(size 0.519938 1.4986)
			(layers "F.Cu" "F.Mask" "F.Paste")
			(net "M_E_CPU0_SB_CA<5>")
		)
		(pad "226" smd rect
			(at 2.050034 10.625074 90)
			(size 0.519938 1.4986)
			(layers "F.Cu" "F.Mask" "F.Paste")
			(net "GND")
		)
		(pad "227" smd rect
			(at 2.050034 11.474958 90)
			(size 0.519938 1.4986)
			(layers "F.Cu" "F.Mask" "F.Paste")
			(net "M_E_CPU0_SB_PAR")
		)
		(pad "228" smd rect
			(at 2.050034 12.325096 90)
			(size 0.519938 1.4986)
			(layers "F.Cu" "F.Mask" "F.Paste")
			(net "GND")
		)
		(pad "229" smd rect
			(at 2.050034 13.17498 90)
			(size 0.519938 1.4986)
			(layers "F.Cu" "F.Mask" "F.Paste")
			(net "M_E_CPU0_SB_CS_N<1>")
		)
		(pad "230" smd rect
			(at 2.050034 14.025118 90)
			(size 0.519938 1.4986)
			(layers "F.Cu" "F.Mask" "F.Paste")
			(net "GND")
		)
	)
)
